(kicad_pcb
	(version 20260206)
	(generator "pcbnew")
	(generator_version "10.0")
	(general
		(thickness 1.6)
		(legacy_teardrops no)
	)
	(paper "A4")
	(title_block
		(title "15969-1a.1015WZS0858.brd")
		(comment 1 "Tioga Pass / footprints 74-81 of 295")
	)
	(layers
		(0 "F.Cu" signal "TOP")
		(4 "In1.Cu" signal "L2GND")
		(6 "In2.Cu" signal "L3")
		(8 "In3.Cu" signal "L4")
		(10 "In4.Cu" signal "L5GND")
		(2 "B.Cu" signal "BOTTOM")
		(9 "F.Adhes" user "F.Adhesive")
		(11 "B.Adhes" user "B.Adhesive")
		(13 "F.Paste" user "Package Geometry/Pastemask Top")
		(15 "B.Paste" user "Package Geometry/Pastemask Bottom")
		(5 "F.SilkS" user "Ref Des/Silkscreen Top")
		(7 "B.SilkS" user "Ref Des/Silkscreen Bottom")
		(1 "F.Mask" user "Board Geometry/Soldermask Top")
		(3 "B.Mask" user "Board Geometry/Soldermask Bottom")
		(17 "Dwgs.User" user "User.Drawings")
		(19 "Cmts.User" user "User.Comments")
		(21 "Eco1.User" user "User.Eco1")
		(23 "Eco2.User" user "User.Eco2")
		(25 "Edge.Cuts" user "Board Geometry/Outline")
		(27 "Margin" user)
		(31 "F.CrtYd" user "Package Geometry/Place Bound Top")
		(29 "B.CrtYd" user "Package Geometry/Place Bound Bottom")
		(35 "F.Fab" user "Ref Des/Assembly Top")
		(33 "B.Fab" user "Ref Des/Assembly Bottom")
	)
	(footprint ""
		(layer "F.Cu")
		(at 33.0581 -3.6195 -90)
		(property "Reference" "C799"
			(at 0 0 270)
			(layer "F.SilkS")
			(hide yes)
			(effects
				(font
					(size 1.27 1.27)
				)
			)
		)
		(property "Value" "SC22U6D3V5MX-5-GP"
			(at -0.0762 -6.1214 270)
			(unlocked yes)
			(layer "F.Fab")
			(hide yes)
			(effects
				(font
					(size 1.016 1.016)
					(thickness 0.1524)
				)
			)
		)
		(property "Device Type" "C805H56"
			(at -0.0762 -8.1534 270)
			(unlocked yes)
			(layer "F.Fab")
			(hide yes)
			(effects
				(font
					(size 1.016 1.016)
					(thickness 0.1524)
				)
			)
		)
		(duplicate_pad_numbers_are_jumpers no)
		(fp_line
			(start 0.635 0)
			(end -0.635 0)
			(stroke
				(width 0.508)
				(type default)
			)
			(layer "F.SilkS")
		)
		(fp_rect
			(start -0.9652 1.778)
			(end 0.9652 -1.778)
			(stroke
				(width 0)
				(type default)
			)
			(fill no)
			(layer "F.CrtYd")
		)
		(fp_poly
			(pts
				(xy -0.9652 -1.778) (xy 0.9652 -1.778) (xy 0.9652 1.778) (xy -0.9652 1.778)
			)
			(stroke
				(width 0)
				(type default)
			)
			(fill no)
			(layer "F.Fab")
		)
		(pad "1" smd rect
			(at 0 -0.9652 270)
			(size 1.397 1.143)
			(layers "F.Cu" "F.Mask" "F.Paste")
			(net "P3V3")
		)
		(pad "2" smd rect
			(at 0 0.9652 270)
			(size 1.397 1.143)
			(layers "F.Cu" "F.Mask" "F.Paste")
			(net "GND")
		)
	)
	(footprint ""
		(layer "F.Cu")
		(at 132.2324 -7.8232 90)
		(property "Reference" "R146"
			(at 0 0 90)
			(layer "F.SilkS")
			(hide yes)
			(effects
				(font
					(size 1.27 1.27)
				)
			)
		)
		(property "Value" "10KR2F-2-GP"
			(at 0.064008 -3.993896 90)
			(unlocked yes)
			(layer "F.Fab")
			(hide yes)
			(effects
				(font
					(size 1.016 1.016)
					(thickness 0.1524)
				)
			)
		)
		(property "Device Type" "R402H16"
			(at 0.064008 -5.517896 90)
			(unlocked yes)
			(layer "F.Fab")
			(hide yes)
			(effects
				(font
					(size 1.016 1.016)
					(thickness 0.1524)
				)
			)
		)
		(duplicate_pad_numbers_are_jumpers no)
		(fp_line
			(start 0.508 -0.9398)
			(end -0.508 -0.9398)
			(stroke
				(width 0.1524)
				(type default)
			)
			(layer "F.SilkS")
		)
		(fp_line
			(start -0.508 -0.9398)
			(end -0.508 0.9398)
			(stroke
				(width 0.1524)
				(type default)
			)
			(layer "F.SilkS")
		)
		(fp_rect
			(start -0.508 0.9398)
			(end 0.508 -0.9398)
			(stroke
				(width 0)
				(type default)
			)
			(fill no)
			(layer "F.CrtYd")
		)
		(fp_rect
			(start -0.508 0.9398)
			(end 0.508 -0.9398)
			(stroke
				(width 0)
				(type default)
			)
			(fill no)
			(layer "F.Fab")
		)
		(pad "1" smd custom
			(at 0 -0.4445 90)
			(size 0.1397 0.1397)
			(layers "F.Cu" "F.Mask" "F.Paste")
			(net "GPIO_P_EXP_A1")
			(options
				(clearance outline)
				(anchor circle)
			)
			(primitives
				(gr_poly
					(pts
						(arc
							(start -0.1778 -0.2794)
							(mid -0.249642 -0.249642)
							(end -0.2794 -0.1778)
						)
						(arc
							(start -0.2794 0.1778)
							(mid -0.249642 0.249642)
							(end -0.1778 0.2794)
						)
						(arc
							(start 0.1778 0.2794)
							(mid 0.249642 0.249642)
							(end 0.2794 0.1778)
						)
						(arc
							(start 0.2794 -0.1778)
							(mid 0.249642 -0.249642)
							(end 0.1778 -0.2794)
						)
					)
					(width 0)
					(fill yes)
				)
			)
		)
		(pad "2" smd custom
			(at 0 0.4445 90)
			(size 0.1397 0.1397)
			(layers "F.Cu" "F.Mask" "F.Paste")
			(net "GND")
			(options
				(clearance outline)
				(anchor circle)
			)
			(primitives
				(gr_poly
					(pts
						(arc
							(start -0.1778 -0.2794)
							(mid -0.249642 -0.249642)
							(end -0.2794 -0.1778)
						)
						(arc
							(start -0.2794 0.1778)
							(mid -0.249642 0.249642)
							(end -0.1778 0.2794)
						)
						(arc
							(start 0.1778 0.2794)
							(mid 0.249642 0.249642)
							(end 0.2794 0.1778)
						)
						(arc
							(start 0.2794 -0.1778)
							(mid 0.249642 -0.249642)
							(end 0.1778 -0.2794)
						)
					)
					(width 0)
					(fill yes)
				)
			)
		)
	)
	(footprint ""
		(layer "F.Cu")
		(at 33.44164 -24.08682 180)
		(property "Reference" "R37"
			(at 0 0 180)
			(layer "F.SilkS")
			(hide yes)
			(effects
				(font
					(size 1.27 1.27)
				)
			)
		)
		(property "Value" "0R2F-1-GP"
			(at 0.064008 -3.993896 180)
			(unlocked yes)
			(layer "F.Fab")
			(hide yes)
			(effects
				(font
					(size 1.016 1.016)
					(thickness 0.1524)
				)
			)
		)
		(property "Device Type" "R402H16"
			(at 0.064008 -5.517896 180)
			(unlocked yes)
			(layer "F.Fab")
			(hide yes)
			(effects
				(font
					(size 1.016 1.016)
					(thickness 0.1524)
				)
			)
		)
		(duplicate_pad_numbers_are_jumpers no)
		(fp_line
			(start 0.508 -0.9398)
			(end -0.508 -0.9398)
			(stroke
				(width 0.1524)
				(type default)
			)
			(layer "F.SilkS")
		)
		(fp_line
			(start -0.508 -0.9398)
			(end -0.508 0.9398)
			(stroke
				(width 0.1524)
				(type default)
			)
			(layer "F.SilkS")
		)
		(fp_rect
			(start -0.508 0.9398)
			(end 0.508 -0.9398)
			(stroke
				(width 0)
				(type default)
			)
			(fill no)
			(layer "F.CrtYd")
		)
		(fp_rect
			(start -0.508 0.9398)
			(end 0.508 -0.9398)
			(stroke
				(width 0)
				(type default)
			)
			(fill no)
			(layer "F.Fab")
		)
		(pad "1" smd custom
			(at 0 -0.4445 180)
			(size 0.1397 0.1397)
			(layers "F.Cu" "F.Mask" "F.Paste")
			(net "SMDAT_PCH_SLOT3")
			(options
				(clearance outline)
				(anchor circle)
			)
			(primitives
				(gr_poly
					(pts
						(arc
							(start -0.1778 -0.2794)
							(mid -0.249642 -0.249642)
							(end -0.2794 -0.1778)
						)
						(arc
							(start -0.2794 0.1778)
							(mid -0.249642 0.249642)
							(end -0.1778 0.2794)
						)
						(arc
							(start 0.1778 0.2794)
							(mid 0.249642 0.249642)
							(end 0.2794 0.1778)
						)
						(arc
							(start 0.2794 -0.1778)
							(mid 0.249642 -0.249642)
							(end 0.1778 -0.2794)
						)
					)
					(width 0)
					(fill yes)
				)
			)
		)
		(pad "2" smd custom
			(at 0 0.4445 180)
			(size 0.1397 0.1397)
			(layers "F.Cu" "F.Mask" "F.Paste")
			(net "SMDAT_PCH_SLOT3_R")
			(options
				(clearance outline)
				(anchor circle)
			)
			(primitives
				(gr_poly
					(pts
						(arc
							(start -0.1778 -0.2794)
							(mid -0.249642 -0.249642)
							(end -0.2794 -0.1778)
						)
						(arc
							(start -0.2794 0.1778)
							(mid -0.249642 0.249642)
							(end -0.1778 0.2794)
						)
						(arc
							(start 0.1778 0.2794)
							(mid 0.249642 0.249642)
							(end 0.2794 0.1778)
						)
						(arc
							(start 0.2794 -0.1778)
							(mid 0.249642 -0.249642)
							(end 0.1778 -0.2794)
						)
					)
					(width 0)
					(fill yes)
				)
			)
		)
	)
	(footprint ""
		(layer "F.Cu")
		(at 28.3972 -2.0828 180)
		(property "Reference" "PC5"
			(at 0 0 180)
			(layer "F.SilkS")
			(hide yes)
			(effects
				(font
					(size 1.27 1.27)
				)
			)
		)
		(property "Value" "SCD1U16V3KX-3GP"
			(at 0 -2.8194 180)
			(unlocked yes)
			(layer "F.Fab")
			(hide yes)
			(effects
				(font
					(size 1.016 1.016)
					(thickness 0.1524)
				)
			)
		)
		(property "Device Type" "C603H36"
			(at 0 -4.3434 180)
			(unlocked yes)
			(layer "F.Fab")
			(hide yes)
			(effects
				(font
					(size 1.016 1.016)
					(thickness 0.1524)
				)
			)
		)
		(duplicate_pad_numbers_are_jumpers no)
		(fp_line
			(start 0.508 0)
			(end -0.508 0)
			(stroke
				(width 0.2032)
				(type default)
			)
			(layer "F.SilkS")
		)
		(fp_rect
			(start -0.5842 1.3335)
			(end 0.5842 -1.3335)
			(stroke
				(width 0)
				(type default)
			)
			(fill no)
			(layer "F.CrtYd")
		)
		(fp_rect
			(start -0.5842 1.3335)
			(end 0.5842 -1.3335)
			(stroke
				(width 0)
				(type default)
			)
			(fill no)
			(layer "F.Fab")
		)
		(pad "1" smd custom
			(at 0 -0.762 180)
			(size 0.2159 0.2159)
			(layers "F.Cu" "F.Mask" "F.Paste")
			(net "P3V3_VR")
			(options
				(clearance outline)
				(anchor circle)
			)
			(primitives
				(gr_poly
					(pts
						(arc
							(start -0.3302 -0.4318)
							(mid -0.402042 -0.402042)
							(end -0.4318 -0.3302)
						)
						(arc
							(start -0.4318 0.3302)
							(mid -0.402042 0.402042)
							(end -0.3302 0.4318)
						)
						(arc
							(start 0.3302 0.4318)
							(mid 0.402042 0.402042)
							(end 0.4318 0.3302)
						)
						(arc
							(start 0.4318 -0.3302)
							(mid 0.402042 -0.402042)
							(end 0.3302 -0.4318)
						)
					)
					(width 0)
					(fill yes)
				)
			)
		)
		(pad "2" smd custom
			(at 0 0.762 180)
			(size 0.2159 0.2159)
			(layers "F.Cu" "F.Mask" "F.Paste")
			(net "GND")
			(options
				(clearance outline)
				(anchor circle)
			)
			(primitives
				(gr_poly
					(pts
						(arc
							(start -0.3302 -0.4318)
							(mid -0.402042 -0.402042)
							(end -0.4318 -0.3302)
						)
						(arc
							(start -0.4318 0.3302)
							(mid -0.402042 0.402042)
							(end -0.3302 0.4318)
						)
						(arc
							(start 0.3302 0.4318)
							(mid 0.402042 0.402042)
							(end 0.4318 0.3302)
						)
						(arc
							(start 0.4318 -0.3302)
							(mid 0.402042 -0.402042)
							(end 0.3302 -0.4318)
						)
					)
					(width 0)
					(fill yes)
				)
			)
		)
	)
	(footprint ""
		(layer "F.Cu")
		(at 26.1874 -7.239 -90)
		(property "Reference" "C13"
			(at 0 0 270)
			(layer "F.SilkS")
			(hide yes)
			(effects
				(font
					(size 1.27 1.27)
				)
			)
		)
		(property "Value" "SCD1U25V3KX-GP"
			(at 0 -2.8194 270)
			(unlocked yes)
			(layer "F.Fab")
			(hide yes)
			(effects
				(font
					(size 1.016 1.016)
					(thickness 0.1524)
				)
			)
		)
		(property "Device Type" "C603H36"
			(at 0 -4.3434 270)
			(unlocked yes)
			(layer "F.Fab")
			(hide yes)
			(effects
				(font
					(size 1.016 1.016)
					(thickness 0.1524)
				)
			)
		)
		(duplicate_pad_numbers_are_jumpers no)
		(fp_line
			(start 0.508 0)
			(end -0.508 0)
			(stroke
				(width 0.2032)
				(type default)
			)
			(layer "F.SilkS")
		)
		(fp_rect
			(start -0.5842 1.3335)
			(end 0.5842 -1.3335)
			(stroke
				(width 0)
				(type default)
			)
			(fill no)
			(layer "F.CrtYd")
		)
		(fp_rect
			(start -0.5842 1.3335)
			(end 0.5842 -1.3335)
			(stroke
				(width 0)
				(type default)
			)
			(fill no)
			(layer "F.Fab")
		)
		(pad "1" smd custom
			(at 0 -0.762 270)
			(size 0.2159 0.2159)
			(layers "F.Cu" "F.Mask" "F.Paste")
			(net "P12V_SLOT2")
			(options
				(clearance outline)
				(anchor circle)
			)
			(primitives
				(gr_poly
					(pts
						(arc
							(start -0.3302 -0.4318)
							(mid -0.402042 -0.402042)
							(end -0.4318 -0.3302)
						)
						(arc
							(start -0.4318 0.3302)
							(mid -0.402042 0.402042)
							(end -0.3302 0.4318)
						)
						(arc
							(start 0.3302 0.4318)
							(mid 0.402042 0.402042)
							(end 0.4318 0.3302)
						)
						(arc
							(start 0.4318 -0.3302)
							(mid 0.402042 -0.402042)
							(end 0.3302 -0.4318)
						)
					)
					(width 0)
					(fill yes)
				)
			)
		)
		(pad "2" smd custom
			(at 0 0.762 270)
			(size 0.2159 0.2159)
			(layers "F.Cu" "F.Mask" "F.Paste")
			(net "GND")
			(options
				(clearance outline)
				(anchor circle)
			)
			(primitives
				(gr_poly
					(pts
						(arc
							(start -0.3302 -0.4318)
							(mid -0.402042 -0.402042)
							(end -0.4318 -0.3302)
						)
						(arc
							(start -0.4318 0.3302)
							(mid -0.402042 0.402042)
							(end -0.3302 0.4318)
						)
						(arc
							(start 0.3302 0.4318)
							(mid 0.402042 0.402042)
							(end 0.4318 0.3302)
						)
						(arc
							(start 0.4318 -0.3302)
							(mid 0.402042 -0.402042)
							(end 0.3302 -0.4318)
						)
					)
					(width 0)
					(fill yes)
				)
			)
		)
	)
	(footprint ""
		(layer "F.Cu")
		(at 130.4036 -24.4856 90)
		(property "Reference" "RU33"
			(at 0 0 90)
			(layer "F.SilkS")
			(hide yes)
			(effects
				(font
					(size 1.27 1.27)
				)
			)
		)
		(property "Value" "100KR2F-L1-GP"
			(at 0.064008 -3.993896 90)
			(unlocked yes)
			(layer "F.Fab")
			(hide yes)
			(effects
				(font
					(size 1.016 1.016)
					(thickness 0.1524)
				)
			)
		)
		(property "Device Type" "R402H16"
			(at 0.064008 -5.517896 90)
			(unlocked yes)
			(layer "F.Fab")
			(hide yes)
			(effects
				(font
					(size 1.016 1.016)
					(thickness 0.1524)
				)
			)
		)
		(duplicate_pad_numbers_are_jumpers no)
		(fp_line
			(start 0.508 -0.9398)
			(end -0.508 -0.9398)
			(stroke
				(width 0.1524)
				(type default)
			)
			(layer "F.SilkS")
		)
		(fp_line
			(start -0.508 -0.9398)
			(end -0.508 0.9398)
			(stroke
				(width 0.1524)
				(type default)
			)
			(layer "F.SilkS")
		)
		(fp_rect
			(start -0.508 0.9398)
			(end 0.508 -0.9398)
			(stroke
				(width 0)
				(type default)
			)
			(fill no)
			(layer "F.CrtYd")
		)
		(fp_rect
			(start -0.508 0.9398)
			(end 0.508 -0.9398)
			(stroke
				(width 0)
				(type default)
			)
			(fill no)
			(layer "F.Fab")
		)
		(pad "1" smd custom
			(at 0 -0.4445 90)
			(size 0.1397 0.1397)
			(layers "F.Cu" "F.Mask" "F.Paste")
			(net "NON_REM0")
			(options
				(clearance outline)
				(anchor circle)
			)
			(primitives
				(gr_poly
					(pts
						(arc
							(start -0.1778 -0.2794)
							(mid -0.249642 -0.249642)
							(end -0.2794 -0.1778)
						)
						(arc
							(start -0.2794 0.1778)
							(mid -0.249642 0.249642)
							(end -0.1778 0.2794)
						)
						(arc
							(start 0.1778 0.2794)
							(mid 0.249642 0.249642)
							(end 0.2794 0.1778)
						)
						(arc
							(start 0.2794 -0.1778)
							(mid 0.249642 -0.249642)
							(end 0.1778 -0.2794)
						)
					)
					(width 0)
					(fill yes)
				)
			)
		)
		(pad "2" smd custom
			(at 0 0.4445 90)
			(size 0.1397 0.1397)
			(layers "F.Cu" "F.Mask" "F.Paste")
			(net "GND")
			(options
				(clearance outline)
				(anchor circle)
			)
			(primitives
				(gr_poly
					(pts
						(arc
							(start -0.1778 -0.2794)
							(mid -0.249642 -0.249642)
							(end -0.2794 -0.1778)
						)
						(arc
							(start -0.2794 0.1778)
							(mid -0.249642 0.249642)
							(end -0.1778 0.2794)
						)
						(arc
							(start 0.1778 0.2794)
							(mid 0.249642 0.249642)
							(end 0.2794 0.1778)
						)
						(arc
							(start 0.2794 -0.1778)
							(mid 0.249642 -0.249642)
							(end 0.1778 -0.2794)
						)
					)
					(width 0)
					(fill yes)
				)
			)
		)
	)
	(footprint ""
		(layer "F.Cu")
		(at 127.9144 0.4826 180)
		(property "Reference" "R145"
			(at 0 0 180)
			(layer "F.SilkS")
			(hide yes)
			(effects
				(font
					(size 1.27 1.27)
				)
			)
		)
		(property "Value" "10KR2F-2-GP"
			(at 0.064008 -3.993896 180)
			(unlocked yes)
			(layer "F.Fab")
			(hide yes)
			(effects
				(font
					(size 1.016 1.016)
					(thickness 0.1524)
				)
			)
		)
		(property "Device Type" "R402H16"
			(at 0.064008 -5.517896 180)
			(unlocked yes)
			(layer "F.Fab")
			(hide yes)
			(effects
				(font
					(size 1.016 1.016)
					(thickness 0.1524)
				)
			)
		)
		(duplicate_pad_numbers_are_jumpers no)
		(fp_line
			(start 0.508 -0.9398)
			(end -0.508 -0.9398)
			(stroke
				(width 0.1524)
				(type default)
			)
			(layer "F.SilkS")
		)
		(fp_line
			(start -0.508 -0.9398)
			(end -0.508 0.9398)
			(stroke
				(width 0.1524)
				(type default)
			)
			(layer "F.SilkS")
		)
		(fp_rect
			(start -0.508 0.9398)
			(end 0.508 -0.9398)
			(stroke
				(width 0)
				(type default)
			)
			(fill no)
			(layer "F.CrtYd")
		)
		(fp_rect
			(start -0.508 0.9398)
			(end 0.508 -0.9398)
			(stroke
				(width 0)
				(type default)
			)
			(fill no)
			(layer "F.Fab")
		)
		(pad "1" smd custom
			(at 0 -0.4445 180)
			(size 0.1397 0.1397)
			(layers "F.Cu" "F.Mask" "F.Paste")
			(net "P3V3_STBY")
			(options
				(clearance outline)
				(anchor circle)
			)
			(primitives
				(gr_poly
					(pts
						(arc
							(start -0.1778 -0.2794)
							(mid -0.249642 -0.249642)
							(end -0.2794 -0.1778)
						)
						(arc
							(start -0.2794 0.1778)
							(mid -0.249642 0.249642)
							(end -0.1778 0.2794)
						)
						(arc
							(start 0.1778 0.2794)
							(mid 0.249642 0.249642)
							(end 0.2794 0.1778)
						)
						(arc
							(start 0.2794 -0.1778)
							(mid 0.249642 -0.249642)
							(end 0.1778 -0.2794)
						)
					)
					(width 0)
					(fill yes)
				)
			)
		)
		(pad "2" smd custom
			(at 0 0.4445 180)
			(size 0.1397 0.1397)
			(layers "F.Cu" "F.Mask" "F.Paste")
			(net "GPIO_P_EXP_A0")
			(options
				(clearance outline)
				(anchor circle)
			)
			(primitives
				(gr_poly
					(pts
						(arc
							(start -0.1778 -0.2794)
							(mid -0.249642 -0.249642)
							(end -0.2794 -0.1778)
						)
						(arc
							(start -0.2794 0.1778)
							(mid -0.249642 0.249642)
							(end -0.1778 0.2794)
						)
						(arc
							(start 0.1778 0.2794)
							(mid 0.249642 0.249642)
							(end 0.2794 0.1778)
						)
						(arc
							(start 0.2794 -0.1778)
							(mid 0.249642 -0.249642)
							(end 0.1778 -0.2794)
						)
					)
					(width 0)
					(fill yes)
				)
			)
		)
	)
	(footprint ""
		(layer "F.Cu")
		(at 112.3188 3.7592)
		(property "Reference" "C57"
			(at 0 0 0)
			(layer "F.SilkS")
			(hide yes)
			(effects
				(font
					(size 1.27 1.27)
				)
			)
		)
		(property "Value" "SCD1U16V2KX-3GP"
			(at 1.1811 -2.7051 0)
			(unlocked yes)
			(layer "F.Fab")
			(hide yes)
			(effects
				(font
					(size 1.016 1.016)
					(thickness 0.1524)
				)
			)
		)
		(property "Device Type" "C402H22"
			(at 1.1811 -4.2291 0)
			(unlocked yes)
			(layer "F.Fab")
			(hide yes)
			(effects
				(font
					(size 1.016 1.016)
					(thickness 0.1524)
				)
			)
		)
		(duplicate_pad_numbers_are_jumpers no)
		(fp_rect
			(start -0.4318 0.9525)
			(end 0.4318 -0.9525)
			(stroke
				(width 0)
				(type default)
			)
			(fill no)
			(layer "F.CrtYd")
		)
		(fp_rect
			(start -0.4318 0.9525)
			(end 0.4318 -0.9525)
			(stroke
				(width 0)
				(type default)
			)
			(fill no)
			(layer "F.Fab")
		)
		(pad "1" smd custom
			(at 0 -0.4445)
			(size 0.1524 0.1524)
			(layers "F.Cu" "F.Mask" "F.Paste")
			(net "P3V3_STBY")
			(options
				(clearance outline)
				(anchor circle)
			)
			(primitives
				(gr_poly
					(pts
						(arc
							(start 0.3048 -0.2032)
							(mid 0.275042 -0.275042)
							(end 0.2032 -0.3048)
						)
						(arc
							(start -0.2032 -0.3048)
							(mid -0.275042 -0.275042)
							(end -0.3048 -0.2032)
						)
						(arc
							(start -0.3048 0.2032)
							(mid -0.275042 0.275042)
							(end -0.2032 0.3048)
						)
						(arc
							(start 0.2032 0.3048)
							(mid 0.275042 0.275042)
							(end 0.3048 0.2032)
						)
					)
					(width 0)
					(fill yes)
				)
			)
		)
		(pad "2" smd custom
			(at 0 0.4445)
			(size 0.1524 0.1524)
			(layers "F.Cu" "F.Mask" "F.Paste")
			(net "GND")
			(options
				(clearance outline)
				(anchor circle)
			)
			(primitives
				(gr_poly
					(pts
						(arc
							(start 0.3048 -0.2032)
							(mid 0.275042 -0.275042)
							(end 0.2032 -0.3048)
						)
						(arc
							(start -0.2032 -0.3048)
							(mid -0.275042 -0.275042)
							(end -0.3048 -0.2032)
						)
						(arc
							(start -0.3048 0.2032)
							(mid -0.275042 0.275042)
							(end -0.2032 0.3048)
						)
						(arc
							(start 0.2032 0.3048)
							(mid 0.275042 0.275042)
							(end 0.3048 0.2032)
						)
					)
					(width 0)
					(fill yes)
				)
			)
		)
	)
)
